# T6G (Grand Teton) — schematic netlist excerpt (pin names and nets, part order shuffled) for the footprints in the layout excerpt that follows; sources: Cadence DE-HDL packaged netlist, KiCad conversion of 04192023_DAF0TMB3IC0_F0TG_MB_C_brd_V02_OCP.brd

J18  SCONN288_DDR506112002KQ  IO  pkg DDR288S_1-1VXC  page 94
  VIN_BULK0  = P12V_MEM_CPU0
  RFU0  = NC
  VIN_MGMT  = P3V3_AUX
  HSCL  = I3C_SPD_DDRI_CPU0_SCL
  HSDA  = I3C_SPD_DDRI_CPU0_SDA
  VSS0  = GND
  DQ0_A  = M_I_CPU0_SA_DQ<0>
  VSS1  = GND
  DQ1_A  = M_I_CPU0_SA_DQ<1>
  VSS2  = GND
  DQS0_A_T  = M_I_CPU0_SA_DQS_DP<0>
  DQS0_A_C  = M_I_CPU0_SA_DQS_DN<0>
  VSS3  = GND
  DQ4_A  = M_I_CPU0_SA_DQ<4>
  VSS4  = GND
  DQ5_A  = M_I_CPU0_SA_DQ<5>
  VSS5  = GND
  DQ8_A  = M_I_CPU0_SA_DQ<8>
  VSS6  = GND
  DQ9_A  = M_I_CPU0_SA_DQ<9>
  VSS7  = GND
  DQS1_A_T  = M_I_CPU0_SA_DQS_DP<1>
  DQS1_A_C  = M_I_CPU0_SA_DQS_DN<1>
  VSS8  = GND
  DQ12_A  = M_I_CPU0_SA_DQ<12>
  VSS9  = GND
  DQ13_A  = M_I_CPU0_SA_DQ<13>
  VSS10  = GND
  DQ16_A  = M_I_CPU0_SA_DQ<16>
  VSS11  = GND
  DQ17_A  = M_I_CPU0_SA_DQ<17>
  VSS12  = GND
  DQS2_A_T  = M_I_CPU0_SA_DQS_DP<2>
  DQS2_A_C  = M_I_CPU0_SA_DQS_DN<2>
  VSS13  = GND
  DQ20_A  = M_I_CPU0_SA_DQ<20>
  VSS14  = GND
  DQ21_A  = M_I_CPU0_SA_DQ<21>
  VSS15  = GND
  DQ24_A  = M_I_CPU0_SA_DQ<24>
  VSS16  = GND
  DQ25_A  = M_I_CPU0_SA_DQ<25>
  VSS17  = GND
  DQS3_A_T  = M_I_CPU0_SA_DQS_DP<3>
  DQS3_A_C  = M_I_CPU0_SA_DQS_DN<3>
  VSS18  = GND
  DQ28_A  = M_I_CPU0_SA_DQ<28>
  VSS19  = GND
  DQ29_A  = M_I_CPU0_SA_DQ<29>
  VSS20  = GND
  CB0_A  = M_I_CPU0_SA_CB<0>
  VSS21  = GND
  CB1_A  = M_I_CPU0_SA_CB<1>
  VSS22  = GND
  DQS4_A_T  = M_I_CPU0_SA_DQS_DP<4>
  DQS4_A_C  = M_I_CPU0_SA_DQS_DN<4>
  VSS23  = GND
  CB4_A  = M_I_CPU0_SA_CB<4>
  VSS24  = GND
  CB5_A  = M_I_CPU0_SA_CB<5>
  VSS25  = GND
  ALERT_N  = M_I_CPU0_ALERT_N
  VSS26  = GND
  CS0_A_N  = M_I_CPU0_SA_CS_N<0>
  VSS27  = GND
  CA0_A  = M_I_CPU0_SA_CA<0>
  VSS28  = GND
  CA2_A  = M_I_CPU0_SA_CA<2>
  VSS29  = GND
  CA4_A  = M_I_CPU0_SA_CA<4>
  VSS30  = GND
  CA6_A  = M_I_CPU0_SA_CA<6>
  VSS31  = GND
  PAR_A  = M_I_CPU0_SA_PAR
  VSS32  = GND
  CA0_B  = M_I_CPU0_SB_CA<0>
  VSS33  = GND
  CA2_B  = M_I_CPU0_SB_CA<2>
  VSS34  = GND
  CA4_B  = M_I_CPU0_SB_CA<4>
  VSS35  = GND
  CA6_B  = M_I_CPU0_SB_CA<6>
  VSS36  = GND
  CS0_B_N  = M_I_CPU0_SB_CS_N<0>
  VSS37  = GND
  \lbd||rsp_a_n\  = M_I_CPU0_SA_RSP<0>
  \lbs||rsp_b_n\  = M_I_CPU0_SB_RSP<0>
  VSS38  = GND
  CB4_B  = M_I_CPU0_SB_CB<4>
  VSS39  = GND
  CB5_B  = M_I_CPU0_SB_CB<5>
  VSS40  = GND
  \dqs9_b_t||tdqs9_b_t||dbi4_b_n\  = M_I_CPU0_SB_DQS_DP<9>
  \dqs9_b_c||tdqs9_b_c\  = M_I_CPU0_SB_DQS_DN<9>
  VSS41  = GND
  CB0_B  = M_I_CPU0_SB_CB<0>
  VSS42  = GND
  CB1_B  = M_I_CPU0_SB_CB<1>
  VSS43  = GND
  DQ0_B  = M_I_CPU0_SB_DQ<0>
  VSS44  = GND
  DQ1_B  = M_I_CPU0_SB_DQ<1>
  VSS45  = GND
  DQS0_B_T  = M_I_CPU0_SB_DQS_DP<0>
  DQS0_B_C  = M_I_CPU0_SB_DQS_DN<0>
  VSS46  = GND
  DQ4_B  = M_I_CPU0_SB_DQ<4>
  VSS47  = GND
  DQ5_B  = M_I_CPU0_SB_DQ<5>
  VSS48  = GND
  DQ8_B  = M_I_CPU0_SB_DQ<8>
  VSS49  = GND
  DQ9_B  = M_I_CPU0_SB_DQ<9>
  VSS50  = GND
  DQS1_B_T  = M_I_CPU0_SB_DQS_DP<1>
  DQS1_B_C  = M_I_CPU0_SB_DQS_DN<1>
  VSS51  = GND
  DQ12_B  = M_I_CPU0_SB_DQ<12>
  VSS52  = GND
  DQ13_B  = M_I_CPU0_SB_DQ<13>
  VSS53  = GND
  DQ16_B  = M_I_CPU0_SB_DQ<16>
  VSS54  = GND
  DQ17_B  = M_I_CPU0_SB_DQ<17>
  VSS55  = GND
  DQS2_B_T  = M_I_CPU0_SB_DQS_DP<2>
  DQS2_B_C  = M_I_CPU0_SB_DQS_DN<2>
  VSS56  = GND
  DQ20_B  = M_I_CPU0_SB_DQ<20>
  VSS57  = GND
  DQ21_B  = M_I_CPU0_SB_DQ<21>
  VSS58  = GND
  DQ24_B  = M_I_CPU0_SB_DQ<24>
  VSS59  = GND
  DQ25_B  = M_I_CPU0_SB_DQ<25>
  VSS60  = GND
  DQS3_B_T  = M_I_CPU0_SB_DQS_DP<3>
  DQS3_B_C  = M_I_CPU0_SB_DQS_DN<3>
  VSS61  = GND
  DQ28_B  = M_I_CPU0_SB_DQ<28>
  VSS62  = GND
  DQ29_B  = M_I_CPU0_SB_DQ<29>
  VSS63  = GND
  RFU1  = NC
  VIN_BULK1  = P12V_MEM_CPU0
  VIN_BULK2  = P12V_MEM_CPU0
  \pwr_good||fail_n\  = PWRGD_CHI_CPU0_DIMM
  HAS  = PD_CHI_CPU0_DIMM_SAA
  RFU2  = NC
  RFU3  = NC
  VSS64  = GND
  DQ2_A  = M_I_CPU0_SA_DQ<2>
  VSS65  = GND
  DQ3_A  = M_I_CPU0_SA_DQ<3>
  VSS66  = GND
  \dqs5_a_c||tdqs5_a_c||dqs5_a_t||tdqs5_a_t\  = M_I_CPU0_SA_DQS_DN<5>
  \dqs5_a_t||tdqs5_a_t\  = M_I_CPU0_SA_DQS_DP<5>
  VSS67  = GND
  DQ6_A  = M_I_CPU0_SA_DQ<6>
  VSS68  = GND
  DQ7_A  = M_I_CPU0_SA_DQ<7>
  VSS69  = GND
  DQ10_A  = M_I_CPU0_SA_DQ<10>
  VSS70  = GND
  DQ11_A  = M_I_CPU0_SA_DQ<11>
  VSS71  = GND
  \dqs6_a_c||tdqs6_a_c||dqs6_a_t||tdqs6_a_t\  = M_I_CPU0_SA_DQS_DN<6>
  \dqs6_a_t||tdqs6_a_t\  = M_I_CPU0_SA_DQS_DP<6>
  VSS72  = GND
  DQ14_A  = M_I_CPU0_SA_DQ<14>
  VSS73  = GND
  DQ15_A  = M_I_CPU0_SA_DQ<15>
  VSS74  = GND
  DQ18_A  = M_I_CPU0_SA_DQ<18>
  VSS75  = GND
  DQ19_A  = M_I_CPU0_SA_DQ<19>
  VSS76  = GND
  \dqs7_a_c||tdqs7_a_c\  = M_I_CPU0_SA_DQS_DN<7>
  \dqs7_a_t||tdqs7_a_t\  = M_I_CPU0_SA_DQS_DP<7>
  VSS77  = GND
  DQ22_A  = M_I_CPU0_SA_DQ<22>
  VSS78  = GND
  DQ23_A  = M_I_CPU0_SA_DQ<23>
  VSS79  = GND
  DQ26_A  = M_I_CPU0_SA_DQ<26>
  VSS80  = GND
  DQ27_A  = M_I_CPU0_SA_DQ<27>
  VSS81  = GND
  \dqs8_a_c||tdqs8_a_c\  = M_I_CPU0_SA_DQS_DN<8>
  \dqs8_a_t||tdqs8_a_t\  = M_I_CPU0_SA_DQS_DP<8>
  VSS82  = GND
  DQ30_A  = M_I_CPU0_SA_DQ<30>
  VSS83  = GND
  DQ31_A  = M_I_CPU0_SA_DQ<31>
  VSS84  = GND
  CB2_A  = M_I_CPU0_SA_CB<2>
  VSS85  = GND
  CB3_A  = M_I_CPU0_SA_CB<3>
  VSS86  = GND
  \dqs9_a_c||tdqs9_a_c\  = M_I_CPU0_SA_DQS_DN<9>
  \dqs9_a_t||tdqs9_a_t\  = M_I_CPU0_SA_DQS_DP<9>
  VSS87  = GND
  CB6_A  = M_I_CPU0_SA_CB<6>
  VSS88  = GND
  CB7_A  = M_I_CPU0_SA_CB<7>
  VSS89  = GND
  RESET_N  = M_I_CPU0_RESET_N
  VSS90  = GND
  CS1_A_N  = M_I_CPU0_SA_CS_N<1>
  VSS91  = GND
  CA1_A  = M_I_CPU0_SA_CA<1>
  VSS92  = GND
  CA3_A  = M_I_CPU0_SA_CA<3>
  VSS93  = GND
  CA5_A  = M_I_CPU0_SA_CA<5>
  VSS94  = GND
  CK_T  = M_I_CPU0_CLK_DP<0>
  CK_C  = M_I_CPU0_CLK_DN<0>
  VSS95  = GND
  RFU4  = NC
  CA1_B  = M_I_CPU0_SB_CA<1>
  VSS96  = GND
  CA3_B  = M_I_CPU0_SB_CA<3>
  VSS97  = GND
  CA5_B  = M_I_CPU0_SB_CA<5>
  VSS98  = GND
  PAR_B  = M_I_CPU0_SB_PAR
  VSS99  = GND
  CS1_B_N  = M_I_CPU0_SB_CS_N<1>
  VSS100  = GND
  RFU5  = NC
  RFU6  = NC
  VSS101  = GND
  CB6_B  = M_I_CPU0_SB_CB<6>
  VSS102  = GND
  CB7_B  = M_I_CPU0_SB_CB<7>
  VSS103  = GND
  DQS4_B_C  = M_I_CPU0_SB_DQS_DN<4>
  DQS4_B_T  = M_I_CPU0_SB_DQS_DP<4>
  VSS104  = GND
  CB2_B  = M_I_CPU0_SB_CB<2>
  VSS105  = GND
  CB3_B  = M_I_CPU0_SB_CB<3>
  VSS106  = GND
  DQ2_B  = M_I_CPU0_SB_DQ<2>
  VSS107  = GND
  DQ3_B  = M_I_CPU0_SB_DQ<3>
  VSS108  = GND
  \dqs5_b_c||tdqs5_b_c\  = M_I_CPU0_SB_DQS_DN<5>
  \dqs5_b_t||tdqs5_b_t\  = M_I_CPU0_SB_DQS_DP<5>
  VSS109  = GND
  DQ6_B  = M_I_CPU0_SB_DQ<6>
  VSS110  = GND
  DQ7_B  = M_I_CPU0_SB_DQ<7>
  VSS111  = GND
  DQ10_B  = M_I_CPU0_SB_DQ<10>
  VSS112  = GND
  DQ11_B  = M_I_CPU0_SB_DQ<11>
  VSS113  = GND
  \dqs6_b_c||tdqs6_b_c\  = M_I_CPU0_SB_DQS_DN<6>
  \dqs6_b_t||tdqs6_b_t\  = M_I_CPU0_SB_DQS_DP<6>
  VSS114  = GND
  DQ14_B  = M_I_CPU0_SB_DQ<14>
  VSS115  = GND
  DQ15_B  = M_I_CPU0_SB_DQ<15>
  VSS116  = GND
  DQ18_B  = M_I_CPU0_SB_DQ<18>
  VSS117  = GND
  DQ19_B  = M_I_CPU0_SB_DQ<19>
  VSS118  = GND
  \dqs7_b_c||tdqs7_b_c\  = M_I_CPU0_SB_DQS_DN<7>
  \dqs7_b_t||tdqs7_b_t\  = M_I_CPU0_SB_DQS_DP<7>
  VSS119  = GND
  DQ22_B  = M_I_CPU0_SB_DQ<22>
  VSS120  = GND
  DQ23_B  = M_I_CPU0_SB_DQ<23>
  VSS121  = GND
  DQ26_B  = M_I_CPU0_SB_DQ<26>
  VSS122  = GND
  DQ27_B  = M_I_CPU0_SB_DQ<27>
  VSS123  = GND
  \dqs8_b_c||tdqs8_b_c\  = M_I_CPU0_SB_DQS_DN<8>
  \dqs8_b_t||tdqs8_b_t\  = M_I_CPU0_SB_DQS_DP<8>
  VSS124  = GND
  DQ30_B  = M_I_CPU0_SB_DQ<30>
  VSS125  = GND
  DQ31_B  = M_I_CPU0_SB_DQ<31>
  VSS126  = GND
  G1  = GND
  G2  = GND
  G3  = GND

(kicad_pcb
	(version 20260206)
	(generator "pcbnew")
	(generator_version "10.0")
	(general
		(thickness 1.6)
		(legacy_teardrops no)
	)
	(paper "A4")
	(title_block
		(title "04192023_DAF0TMB3IC0_F0TG_MB_C_brd_V02_OCP.brd")
		(comment 1 "Grand Teton / footprint 4761 of 8354 (J18), pads 277-291 of 291")
	)
	(layers
		(0 "F.Cu" signal "TOP")
		(4 "In1.Cu" signal "GND")
		(6 "In2.Cu" signal "IN1")
		(8 "In3.Cu" signal "GND1")
		(10 "In4.Cu" signal "IN2")
		(12 "In5.Cu" signal "GND2")
		(14 "In6.Cu" signal "IN3")
		(16 "In7.Cu" signal "GND3")
		(18 "In8.Cu" signal "VCC")
		(20 "In9.Cu" signal "VCC1")
		(22 "In10.Cu" signal "GND4")
		(24 "In11.Cu" signal "IN4")
		(26 "In12.Cu" signal "GND5")
		(28 "In13.Cu" signal "IN5")
		(30 "In14.Cu" signal "GND6")
		(32 "In15.Cu" signal "IN6")
		(34 "In16.Cu" signal "GND7")
		(2 "B.Cu" signal "BOTTOM")
		(9 "F.Adhes" user "F.Adhesive")
		(11 "B.Adhes" user "B.Adhesive")
		(13 "F.Paste" user "Package Geometry/Pastemask Top")
		(15 "B.Paste" user "Package Geometry/Pastemask Bottom")
		(5 "F.SilkS" user "Ref Des/Silkscreen Top")
		(7 "B.SilkS" user "Ref Des/Silkscreen Bottom")
		(1 "F.Mask" user "Board Geometry/Soldermask Top")
		(3 "B.Mask" user "Board Geometry/Soldermask Bottom")
		(17 "Dwgs.User" user "User.Drawings")
		(19 "Cmts.User" user "User.Comments")
		(21 "Eco1.User" user "User.Eco1")
		(23 "Eco2.User" user "User.Eco2")
		(25 "Edge.Cuts" user "Board Geometry/Outline")
		(27 "Margin" user)
		(31 "F.CrtYd" user "Package Geometry/Place Bound Top")
		(29 "B.CrtYd" user "Package Geometry/Place Bound Bottom")
		(35 "F.Fab" user "Ref Des/Assembly Top")
		(33 "B.Fab" user "Ref Des/Assembly Bottom")
	)
	(footprint ""
		(layer "F.Cu")
		(at 429.506126 -255.560068 180)
		(property "Reference" "J18"
			(at 0.484632 -81.752948 0)
			(unlocked yes)
			(layer "F.SilkS")
			(effects
				(font
					(size 0.7874 0.5842)
					(thickness 0.1524)
				)
			)
		)
		(property "Value" ""
			(at 0 0 180)
			(layer "F.Fab")
			(effects
				(font
					(size 1.27 1.27)
				)
			)
		)
		(duplicate_pad_numbers_are_jumpers no)
		(pad "277" smd rect
			(at 2.050034 53.975 90)
			(size 0.519938 1.4986)
			(layers "F.Cu" "F.Mask" "F.Paste")
			(net "GND")
		)
		(pad "278" smd rect
			(at 2.050034 54.824884 90)
			(size 0.519938 1.4986)
			(layers "F.Cu" "F.Mask" "F.Paste")
			(net "M_I_CPU0_SB_DQ<26>")
		)
		(pad "279" smd rect
			(at 2.050034 55.675022 90)
			(size 0.519938 1.4986)
			(layers "F.Cu" "F.Mask" "F.Paste")
			(net "GND")
		)
		(pad "280" smd rect
			(at 2.050034 56.524906 90)
			(size 0.519938 1.4986)
			(layers "F.Cu" "F.Mask" "F.Paste")
			(net "M_I_CPU0_SB_DQ<27>")
		)
		(pad "281" smd rect
			(at 2.050034 57.375044 90)
			(size 0.519938 1.4986)
			(layers "F.Cu" "F.Mask" "F.Paste")
			(net "GND")
		)
		(pad "282" smd rect
			(at 2.050034 58.224928 90)
			(size 0.519938 1.4986)
			(layers "F.Cu" "F.Mask" "F.Paste")
			(net "M_I_CPU0_SB_DQS_DN<8>")
		)
		(pad "283" smd rect
			(at 2.050034 59.075066 90)
			(size 0.519938 1.4986)
			(layers "F.Cu" "F.Mask" "F.Paste")
			(net "M_I_CPU0_SB_DQS_DP<8>")
		)
		(pad "284" smd rect
			(at 2.050034 59.92495 90)
			(size 0.519938 1.4986)
			(layers "F.Cu" "F.Mask" "F.Paste")
			(net "GND")
		)
		(pad "285" smd rect
			(at 2.050034 60.775088 90)
			(size 0.519938 1.4986)
			(layers "F.Cu" "F.Mask" "F.Paste")
			(net "M_I_CPU0_SB_DQ<30>")
		)
		(pad "286" smd rect
			(at 2.050034 61.624972 90)
			(size 0.519938 1.4986)
			(layers "F.Cu" "F.Mask" "F.Paste")
			(net "GND")
		)
		(pad "287" smd rect
			(at 2.050034 62.47511 90)
			(size 0.519938 1.4986)
			(layers "F.Cu" "F.Mask" "F.Paste")
			(net "M_I_CPU0_SB_DQ<31>")
		)
		(pad "288" smd rect
			(at 2.050034 63.324994 90)
			(size 0.519938 1.4986)
			(layers "F.Cu" "F.Mask" "F.Paste")
			(net "GND")
		)
		(pad "G1" thru_hole oval
			(at 0 -68.97497 90)
			(size 1.7272 3.4798)
			(drill oval 1.2192 2.4638)
			(layers "*.Cu" "*.Mask")
			(remove_unused_layers no)
			(net "GND")
			(clearance 0.127)
			(thermal_gap 0.127)
		)
		(pad "G2" thru_hole oval
			(at 0 3.875024 90)
			(size 1.7272 3.4798)
			(drill oval 1.2192 2.4638)
			(layers "*.Cu" "*.Mask")
			(remove_unused_layers no)
			(net "GND")
			(clearance 0.127)
			(thermal_gap 0.127)
		)
		(pad "G3" thru_hole oval
			(at 0 68.97497 90)
			(size 1.7272 3.4798)
			(drill oval 1.2192 2.4638)
			(layers "*.Cu" "*.Mask")
			(remove_unused_layers no)
			(net "GND")
			(clearance 0.127)
			(thermal_gap 0.127)
		)
	)
)
